# BASEBOARD_FAB2 (Tioga Pass) — schematic netlist excerpt (pin names and nets, part order shuffled) for the footprints in the layout excerpt that follows; sources: Cadence DE-HDL packaged netlist, KiCad conversion of Wiwynn_Tioga_Pass_MB.brd

R3P22  RES  0.0 5% CHIP  pkg 0402  page 211 : A = P3V3_STBY ; B = VR_PVCCIO_CPU0_VDD
C2M11  CAP  47UF 4V 20% X6S  pkg 0805  page 131 : A = P1V05_PCH_STBY ; B = GND
C2M22  CAP_A  1.0UF 6.3V 10% X6S  pkg 0402V  page 131 : A = P1V05_PCH_STBY ; B = GND

(kicad_pcb
	(version 20260206)
	(generator "pcbnew")
	(generator_version "10.0")
	(general
		(thickness 1.6)
		(legacy_teardrops no)
	)
	(paper "A4")
	(title_block
		(title "Wiwynn_Tioga_Pass_MB.brd")
		(comment 1 "Tioga Pass / footprints 2461-2463 of 4770")
	)
	(layers
		(0 "F.Cu" signal "TOP")
		(4 "In1.Cu" signal "L2GND")
		(6 "In2.Cu" signal "L3")
		(8 "In3.Cu" signal "L4GND")
		(10 "In4.Cu" signal "L5")
		(12 "In5.Cu" signal "L6GND")
		(14 "In6.Cu" signal "L7VCC")
		(16 "In7.Cu" signal "L8VCC")
		(18 "In8.Cu" signal "L9GND")
		(20 "In9.Cu" signal "L10")
		(22 "In10.Cu" signal "L11GND")
		(24 "In11.Cu" signal "L12")
		(26 "In12.Cu" signal "L13GND")
		(2 "B.Cu" signal "BOTTOM")
		(9 "F.Adhes" user "F.Adhesive")
		(11 "B.Adhes" user "B.Adhesive")
		(13 "F.Paste" user "Package Geometry/Pastemask Top")
		(15 "B.Paste" user "Package Geometry/Pastemask Bottom")
		(5 "F.SilkS" user "Ref Des/Silkscreen Top")
		(7 "B.SilkS" user "Ref Des/Silkscreen Bottom")
		(1 "F.Mask" user "Board Geometry/Soldermask Top")
		(3 "B.Mask" user "Board Geometry/Soldermask Bottom")
		(17 "Dwgs.User" user "User.Drawings")
		(19 "Cmts.User" user "User.Comments")
		(21 "Eco1.User" user "User.Eco1")
		(23 "Eco2.User" user "User.Eco2")
		(25 "Edge.Cuts" user "Board Geometry/Outline")
		(27 "Margin" user)
		(31 "F.CrtYd" user "Package Geometry/Place Bound Top")
		(29 "B.CrtYd" user "Package Geometry/Place Bound Bottom")
		(35 "F.Fab" user "Ref Des/Assembly Top")
		(33 "B.Fab" user "Ref Des/Assembly Bottom")
	)
	(footprint ""
		(layer "B.Cu")
		(at 408.333956 -114.984784 180)
		(property "Reference" "C2M11"
			(at 0 0 0)
			(layer "B.SilkS")
			(hide yes)
			(effects
				(font
					(size 1.27 1.27)
				)
				(justify mirror)
			)
		)
		(property "Value" ""
			(at 0 0 0)
			(layer "B.Fab")
			(effects
				(font
					(size 1.27 1.27)
				)
				(justify mirror)
			)
		)
		(duplicate_pad_numbers_are_jumpers no)
		(fp_poly
			(pts
				(xy 0.7239 -0.2159) (xy -0.7239 -0.2159) (xy -0.7239 1.9939) (xy 0.7239 1.9939)
			)
			(stroke
				(width 0)
				(type default)
			)
			(fill no)
			(layer "B.CrtYd")
		)
		(fp_line
			(start 0.7239 1.9939)
			(end -0.7239 1.9939)
			(stroke
				(width 0.1)
				(type default)
			)
			(layer "B.Fab")
		)
		(fp_line
			(start 0.7239 -0.2159)
			(end 0.7239 1.9939)
			(stroke
				(width 0.1)
				(type default)
			)
			(layer "B.Fab")
		)
		(fp_line
			(start -0.7239 1.9939)
			(end -0.7239 -0.2159)
			(stroke
				(width 0.1)
				(type default)
			)
			(layer "B.Fab")
		)
		(fp_line
			(start -0.7239 -0.2159)
			(end 0.7239 -0.2159)
			(stroke
				(width 0.1)
				(type default)
			)
			(layer "B.Fab")
		)
		(pad "1" smd rect
			(at 0 0)
			(size 1.27 1.016)
			(layers "B.Cu" "B.Mask" "B.Paste")
			(net "P1V05_PCH_STBY")
		)
		(pad "2" smd rect
			(at 0 1.778)
			(size 1.27 1.016)
			(layers "B.Cu" "B.Mask" "B.Paste")
			(net "GND")
		)
		(zone
			(layer "B.Cu")
			(hatch none 0.5)
			(connect_pads
				(clearance 0)
			)
			(min_thickness 0.25)
			(keepout
				(tracks not_allowed)
				(vias allowed)
				(pads allowed)
				(copperpour not_allowed)
				(footprints allowed)
			)
			(placement
				(enabled no)
				(sheetname "")
			)
			(fill
				(thermal_gap 0.5)
				(thermal_bridge_width 0.5)
				(island_removal_mode 0)
			)
			(polygon
				(pts
					(xy 407.698956 -115.492784) (xy 408.968956 -115.492784) (xy 408.968956 -116.254784) (xy 407.698956 -116.254784)
				)
			)
		)
	)
	(footprint ""
		(layer "B.Cu")
		(at 390.13765 -113.45545)
		(property "Reference" "C2M22"
			(at 0 0 0)
			(layer "B.SilkS")
			(hide yes)
			(effects
				(font
					(size 1.27 1.27)
				)
				(justify mirror)
			)
		)
		(property "Value" ""
			(at 0 0 0)
			(layer "B.Fab")
			(effects
				(font
					(size 1.27 1.27)
				)
				(justify mirror)
			)
		)
		(duplicate_pad_numbers_are_jumpers no)
		(fp_rect
			(start 0.2794 0.9144)
			(end -0.2794 -0.1143)
			(stroke
				(width 0)
				(type default)
			)
			(fill no)
			(layer "B.CrtYd")
		)
		(fp_line
			(start -0.2794 -0.1143)
			(end -0.2794 0.9144)
			(stroke
				(width 0.1)
				(type default)
			)
			(layer "B.Fab")
		)
		(fp_line
			(start -0.2794 0.9144)
			(end 0.2794 0.9144)
			(stroke
				(width 0.1)
				(type default)
			)
			(layer "B.Fab")
		)
		(fp_line
			(start 0.2794 -0.1143)
			(end -0.2794 -0.1143)
			(stroke
				(width 0.1)
				(type default)
			)
			(layer "B.Fab")
		)
		(fp_line
			(start 0.2794 0.9144)
			(end 0.2794 -0.1143)
			(stroke
				(width 0.1)
				(type default)
			)
			(layer "B.Fab")
		)
		(pad "1" smd custom
			(at 0 0 270)
			(size 0.10414 0.10414)
			(layers "B.Cu" "B.Mask" "B.Paste")
			(net "P1V05_PCH_STBY")
			(options
				(clearance outline)
				(anchor circle)
			)
			(primitives
				(gr_poly
					(pts
						(xy -0.20828 -0.08636) (xy -0.20828 0.08636) (xy -0.08636 0.20828) (xy 0.086614 0.20828) (xy 0.20828 0.086614)
						(xy 0.20828 -0.08636) (xy 0.08636 -0.20828) (xy -0.08636 -0.20828)
					)
					(width 0)
					(fill yes)
				)
			)
		)
		(pad "2" smd custom
			(at 0 0.8001 270)
			(size 0.10414 0.10414)
			(layers "B.Cu" "B.Mask" "B.Paste")
			(net "GND")
			(options
				(clearance outline)
				(anchor circle)
			)
			(primitives
				(gr_poly
					(pts
						(xy -0.20828 -0.08636) (xy -0.20828 0.08636) (xy -0.08636 0.20828) (xy 0.086614 0.20828) (xy 0.20828 0.086614)
						(xy 0.20828 -0.08636) (xy 0.08636 -0.20828) (xy -0.08636 -0.20828)
					)
					(width 0)
					(fill yes)
				)
			)
		)
		(zone
			(layer "B.Cu")
			(hatch none 0.5)
			(connect_pads
				(clearance 0)
			)
			(min_thickness 0.25)
			(keepout
				(tracks allowed)
				(vias not_allowed)
				(pads allowed)
				(copperpour not_allowed)
				(footprints allowed)
			)
			(placement
				(enabled no)
				(sheetname "")
			)
			(fill
				(thermal_gap 0.5)
				(thermal_bridge_width 0.5)
				(island_removal_mode 0)
			)
			(polygon
				(pts
					(xy 390.22528 -113.2459) (xy 390.22528 -112.8649) (xy 390.05002 -112.8649) (xy 390.049766 -113.2459)
				)
			)
		)
		(zone
			(layer "B.Cu")
			(hatch none 0.5)
			(connect_pads
				(clearance 0)
			)
			(min_thickness 0.25)
			(keepout
				(tracks not_allowed)
				(vias allowed)
				(pads allowed)
				(copperpour not_allowed)
				(footprints allowed)
			)
			(placement
				(enabled no)
				(sheetname "")
			)
			(fill
				(thermal_gap 0.5)
				(thermal_bridge_width 0.5)
				(island_removal_mode 0)
			)
			(polygon
				(pts
					(xy 390.22528 -113.2459) (xy 390.22528 -112.8649) (xy 390.05002 -112.8649) (xy 390.049766 -113.2459)
				)
			)
		)
	)
	(footprint ""
		(layer "B.Cu")
		(at 351.93732 -83.510628 -90)
		(property "Reference" "R3P22"
			(at 0 0 90)
			(layer "B.SilkS")
			(hide yes)
			(effects
				(font
					(size 1.27 1.27)
				)
				(justify mirror)
			)
		)
		(property "Value" ""
			(at 0 0 90)
			(layer "B.Fab")
			(effects
				(font
					(size 1.27 1.27)
				)
				(justify mirror)
			)
		)
		(duplicate_pad_numbers_are_jumpers no)
		(fp_poly
			(pts
				(xy 0.2794 -0.1016) (xy -0.2794 -0.1016) (xy -0.2794 0.9906) (xy 0.2794 0.9906)
			)
			(stroke
				(width 0)
				(type default)
			)
			(fill no)
			(layer "B.CrtYd")
		)
		(fp_line
			(start -0.2794 0.9906)
			(end -0.2794 -0.1016)
			(stroke
				(width 0.1)
				(type default)
			)
			(layer "B.Fab")
		)
		(fp_line
			(start 0.2794 0.9906)
			(end -0.2794 0.9906)
			(stroke
				(width 0.1)
				(type default)
			)
			(layer "B.Fab")
		)
		(fp_line
			(start -0.2794 -0.1016)
			(end 0.2794 -0.1016)
			(stroke
				(width 0.1)
				(type default)
			)
			(layer "B.Fab")
		)
		(fp_line
			(start 0.2794 -0.1016)
			(end 0.2794 0.9906)
			(stroke
				(width 0.1)
				(type default)
			)
			(layer "B.Fab")
		)
		(pad "1" smd rect
			(at 0 0 90)
			(size 0.508 0.508)
			(layers "B.Cu" "B.Mask" "B.Paste")
			(net "P3V3_STBY")
		)
		(pad "2" smd rect
			(at 0 0.889 90)
			(size 0.508 0.508)
			(layers "B.Cu" "B.Mask" "B.Paste")
			(net "VR_PVCCIO_CPU0_VDD")
		)
		(zone
			(layer "B.Cu")
			(hatch none 0.5)
			(connect_pads
				(clearance 0)
			)
			(min_thickness 0.25)
			(keepout
				(tracks not_allowed)
				(vias allowed)
				(pads allowed)
				(copperpour not_allowed)
				(footprints allowed)
			)
			(placement
				(enabled no)
				(sheetname "")
			)
			(fill
				(thermal_gap 0.5)
				(thermal_bridge_width 0.5)
				(island_removal_mode 0)
			)
			(polygon
				(pts
					(xy 351.30232 -83.256628) (xy 351.30232 -83.764628) (xy 351.68332 -83.764628) (xy 351.68332 -83.256628)
				)
			)
		)
		(zone
			(layer "B.Cu")
			(hatch none 0.5)
			(connect_pads
				(clearance 0)
			)
			(min_thickness 0.25)
			(keepout
				(tracks allowed)
				(vias not_allowed)
				(pads allowed)
				(copperpour not_allowed)
				(footprints allowed)
			)
			(placement
				(enabled no)
				(sheetname "")
			)
			(fill
				(thermal_gap 0.5)
				(thermal_bridge_width 0.5)
				(island_removal_mode 0)
			)
			(polygon
				(pts
					(xy 351.68332 -83.256628) (xy 351.68332 -83.764628) (xy 351.30232 -83.764628) (xy 351.30232 -83.256628)
				)
			)
		)
	)
)
